(kicad_pcb
	(version 20240108)
	(generator "pcbnew")
	(generator_version "8.0")
	(general
		(thickness 1.62)
		(legacy_teardrops no)
	)
	(paper "A4")
	(title_block
		(title "Jetson Orin Baseboard")
		(date "2025-03-12")
		(rev "1.3.4")
		(company "Antmicro Ltd")
		(comment 1 "www.antmicro.com")
		(comment 9 "footprints 264-268 of 677")
	)
	(layers
		(0 "F.Cu" signal)
		(1 "In1.Cu" signal)
		(2 "In2.Cu" signal)
		(3 "In3.Cu" signal)
		(4 "In4.Cu" jumper)
		(5 "In5.Cu" signal)
		(6 "In6.Cu" signal)
		(31 "B.Cu" signal)
		(32 "B.Adhes" user "B.Adhesive")
		(33 "F.Adhes" user "F.Adhesive")
		(34 "B.Paste" user)
		(35 "F.Paste" user)
		(36 "B.SilkS" user "B.Silkscreen")
		(37 "F.SilkS" user "F.Silkscreen")
		(38 "B.Mask" user)
		(39 "F.Mask" user)
		(40 "Dwgs.User" user "User.Drawings")
		(41 "Cmts.User" user "User.Comments")
		(42 "Eco1.User" user "User.Eco1")
		(43 "Eco2.User" user "User.Eco2")
		(44 "Edge.Cuts" user)
		(45 "Margin" user)
		(46 "B.CrtYd" user "B.Courtyard")
		(47 "F.CrtYd" user "F.Courtyard")
		(48 "B.Fab" user)
		(49 "F.Fab" user)
	)
	(footprint "antmicro-footprints:C_0402_1005Metric"
		(layer "F.Cu")
		(at 80.08 115.31 -90)
		(descr "Capacitor SMD 0402")
		(tags "capacitor SMD 0402")
		(property "Reference" "C33"
			(at -1.73 0.47 -90)
			(layer "F.SilkS")
			(effects
				(font
					(size 0.7 0.7)
					(thickness 0.15)
				)
				(justify left bottom)
			)
		)
		(property "Value" "C_100n_0402"
			(at 0 1.4 -90)
			(layer "F.Fab")
			(effects
				(font
					(size 0.7 0.7)
					(thickness 0.15)
				)
				(justify left bottom)
			)
		)
		(property "Footprint" "antmicro-footprints:C_0402_1005Metric"
			(at 0 0 -90)
			(layer "F.Fab")
			(hide yes)
			(effects
				(font
					(size 1.27 1.27)
					(thickness 0.15)
				)
			)
		)
		(property "Datasheet" "https://www.murata.com/products/productdetail?partno=GRM155R61H104KE14%23"
			(at 0 0 -90)
			(layer "F.Fab")
			(hide yes)
			(effects
				(font
					(size 1.27 1.27)
					(thickness 0.15)
				)
			)
		)
		(property "Author" "Antmicro"
			(at -35.23 195.39 0)
			(layer "F.Fab")
			(hide yes)
			(effects
				(font
					(size 1 1)
					(thickness 0.15)
				)
			)
		)
		(property "Dielectric" "X5R"
			(at -35.23 195.39 0)
			(layer "F.Fab")
			(hide yes)
			(effects
				(font
					(size 1 1)
					(thickness 0.15)
				)
			)
		)
		(property "License" "Apache-2.0"
			(at -35.23 195.39 0)
			(layer "F.Fab")
			(hide yes)
			(effects
				(font
					(size 1 1)
					(thickness 0.15)
				)
			)
		)
		(property "MPN" "GRM155R61H104KE14D"
			(at -35.23 195.39 0)
			(layer "F.Fab")
			(hide yes)
			(effects
				(font
					(size 1 1)
					(thickness 0.15)
				)
			)
		)
		(property "Manufacturer" "Murata"
			(at -35.23 195.39 0)
			(layer "F.Fab")
			(hide yes)
			(effects
				(font
					(size 1 1)
					(thickness 0.15)
				)
			)
		)
		(property "Val" "100n"
			(at -35.23 195.39 0)
			(layer "F.Fab")
			(hide yes)
			(effects
				(font
					(size 1 1)
					(thickness 0.15)
				)
			)
		)
		(property "Voltage" "50V"
			(at -35.23 195.39 0)
			(layer "F.Fab")
			(hide yes)
			(effects
				(font
					(size 1 1)
					(thickness 0.15)
				)
			)
		)
		(sheetname "USB Debug, DP")
		(sheetfile "usb.kicad_sch")
		(attr smd)
		(fp_rect
			(start -0.925 -0.47)
			(end 0.925 0.47)
			(stroke
				(width 0.05)
				(type default)
			)
			(fill none)
			(layer "F.CrtYd")
		)
		(fp_line
			(start -0.494 0.248)
			(end -0.494 -0.25)
			(stroke
				(width 0.15)
				(type solid)
			)
			(layer "F.Fab")
		)
		(fp_line
			(start 0.504 0.248)
			(end -0.494 0.248)
			(stroke
				(width 0.15)
				(type solid)
			)
			(layer "F.Fab")
		)
		(fp_line
			(start -0.494 -0.25)
			(end 0.504 -0.25)
			(stroke
				(width 0.15)
				(type solid)
			)
			(layer "F.Fab")
		)
		(fp_line
			(start 0.504 -0.25)
			(end 0.504 0.248)
			(stroke
				(width 0.15)
				(type solid)
			)
			(layer "F.Fab")
		)
		(fp_text user "${REFERENCE}"
			(at -0.932 3.168 -90)
			(layer "F.Fab")
			(hide yes)
			(effects
				(font
					(size 0.7 0.7)
					(thickness 0.15)
				)
				(justify left bottom)
			)
		)
		(fp_text user "License: Apache-2.0"
			(at -0.932 5.17 -90)
			(layer "F.Fab")
			(hide yes)
			(effects
				(font
					(size 0.7 0.7)
					(thickness 0.15)
				)
				(justify left bottom)
			)
		)
		(fp_text user "Author: Antmicro"
			(at -0.932 4.17 -90)
			(layer "F.Fab")
			(hide yes)
			(effects
				(font
					(size 0.7 0.7)
					(thickness 0.15)
				)
				(justify left bottom)
			)
		)
		(pad "1" smd roundrect
			(at -0.48 0 270)
			(size 0.59 0.64)
			(layers "F.Cu" "F.Paste" "F.Mask")
			(roundrect_rratio 0.25)
			(net 1 "GND")
			(pintype "passive")
		)
		(pad "2" smd roundrect
			(at 0.48 0 270)
			(size 0.59 0.64)
			(layers "F.Cu" "F.Paste" "F.Mask")
			(roundrect_rratio 0.25)
			(net 98 "EEPROM_PWR")
			(pintype "passive")
		)
	)
	(footprint "antmicro-footprints:R_0402_1005Metric"
		(layer "F.Cu")
		(at 64.05 113.115 -90)
		(descr "Resistor SMD 0402")
		(tags "resistor SMD 0402")
		(property "Reference" "R74"
			(at -1.065 0.4 90)
			(layer "F.SilkS")
			(effects
				(font
					(size 0.7 0.7)
					(thickness 0.15)
				)
				(justify right bottom)
			)
		)
		(property "Value" "R_10k_0402"
			(at 0 1.4 90)
			(layer "F.Fab")
			(effects
				(font
					(size 0.7 0.7)
					(thickness 0.15)
				)
				(justify right bottom)
			)
		)
		(property "Footprint" "antmicro-footprints:R_0402_1005Metric"
			(at 0 0 -90)
			(layer "F.Fab")
			(hide yes)
			(effects
				(font
					(size 1.27 1.27)
					(thickness 0.15)
				)
			)
		)
		(property "Datasheet" "https://www.bourns.com/docs/product-datasheets/cr.pdf"
			(at 0 0 -90)
			(layer "F.Fab")
			(hide yes)
			(effects
				(font
					(size 1.27 1.27)
					(thickness 0.15)
				)
			)
		)
		(property "Author" "Antmicro"
			(at -49.065 177.165 0)
			(layer "F.Fab")
			(hide yes)
			(effects
				(font
					(size 1 1)
					(thickness 0.15)
				)
			)
		)
		(property "License" "Apache-2.0"
			(at -49.065 177.165 0)
			(layer "F.Fab")
			(hide yes)
			(effects
				(font
					(size 1 1)
					(thickness 0.15)
				)
			)
		)
		(property "MPN" "CR0402-FX-1002GLF"
			(at -49.065 177.165 0)
			(layer "F.Fab")
			(hide yes)
			(effects
				(font
					(size 1 1)
					(thickness 0.15)
				)
			)
		)
		(property "Manufacturer" "Bourns"
			(at -49.065 177.165 0)
			(layer "F.Fab")
			(hide yes)
			(effects
				(font
					(size 1 1)
					(thickness 0.15)
				)
			)
		)
		(property "Tolerance" "1%"
			(at -49.065 177.165 0)
			(layer "F.Fab")
			(hide yes)
			(effects
				(font
					(size 1 1)
					(thickness 0.15)
				)
			)
		)
		(property "Val" "10k"
			(at -49.065 177.165 0)
			(layer "F.Fab")
			(hide yes)
			(effects
				(font
					(size 1 1)
					(thickness 0.15)
				)
			)
		)
		(sheetname "USB Debug, DP")
		(sheetfile "usb.kicad_sch")
		(attr smd)
		(fp_rect
			(start -0.925 -0.47)
			(end 0.925 0.47)
			(stroke
				(width 0.05)
				(type default)
			)
			(fill none)
			(layer "F.CrtYd")
		)
		(fp_rect
			(start -0.5 -0.25)
			(end 0.5 0.25)
			(stroke
				(width 0.15)
				(type solid)
			)
			(fill none)
			(layer "F.Fab")
		)
		(fp_text user "${REFERENCE}"
			(at -0.95 3.168 90)
			(layer "F.Fab")
			(hide yes)
			(effects
				(font
					(size 0.7 0.7)
					(thickness 0.15)
				)
				(justify right bottom)
			)
		)
		(fp_text user "Author: Antmicro"
			(at -0.95 4.169 90)
			(layer "F.Fab")
			(hide yes)
			(effects
				(font
					(size 0.7 0.7)
					(thickness 0.15)
				)
				(justify right bottom)
			)
		)
		(fp_text user "License: Apache-2.0"
			(at -0.95 5.169 90)
			(layer "F.Fab")
			(hide yes)
			(effects
				(font
					(size 0.7 0.7)
					(thickness 0.15)
				)
				(justify right bottom)
			)
		)
		(pad "1" smd roundrect
			(at -0.48 0 270)
			(size 0.59 0.64)
			(layers "F.Cu" "F.Paste" "F.Mask")
			(roundrect_rratio 0.25)
			(net 501 "/USB Debug, DP/USBC3_FLG")
			(pintype "passive")
		)
		(pad "2" smd roundrect
			(at 0.48 0 270)
			(size 0.59 0.64)
			(layers "F.Cu" "F.Paste" "F.Mask")
			(roundrect_rratio 0.25)
			(net 99 "+5V")
			(pintype "passive")
		)
	)
	(footprint "antmicro-footprints:R_0402_1005Metric"
		(layer "F.Cu")
		(at 65.91 93.35)
		(descr "Resistor SMD 0402")
		(tags "resistor SMD 0402")
		(property "Reference" "R239"
			(at -1.11 -1.4 0)
			(layer "F.SilkS")
			(effects
				(font
					(size 0.7 0.7)
					(thickness 0.15)
				)
				(justify left bottom)
			)
		)
		(property "Value" "R_499k_0402"
			(at -1.011843 1.772047 0)
			(layer "F.Fab")
			(effects
				(font
					(size 0.7 0.7)
					(thickness 0.15)
				)
				(justify left bottom)
			)
		)
		(property "Footprint" "antmicro-footprints:R_0402_1005Metric"
			(at 0 0 0)
			(layer "F.Fab")
			(hide yes)
			(effects
				(font
					(size 1.27 1.27)
					(thickness 0.15)
				)
			)
		)
		(property "Datasheet" "https://www.mouser.com/datasheet/2/54/cr-1858361.pdf"
			(at 0 0 0)
			(layer "F.Fab")
			(hide yes)
			(effects
				(font
					(size 1.27 1.27)
					(thickness 0.15)
				)
			)
		)
		(property "Author" "Antmicro"
			(at 0 0 0)
			(layer "F.Fab")
			(hide yes)
			(effects
				(font
					(size 1 1)
					(thickness 0.15)
				)
			)
		)
		(property "License" "Apache-2.0"
			(at 0 0 0)
			(layer "F.Fab")
			(hide yes)
			(effects
				(font
					(size 1 1)
					(thickness 0.15)
				)
			)
		)
		(property "MPN" "CR0402-FX-4993GLF"
			(at 0 0 0)
			(layer "F.Fab")
			(hide yes)
			(effects
				(font
					(size 1 1)
					(thickness 0.15)
				)
			)
		)
		(property "Manufacturer" "Bourns"
			(at 0 0 0)
			(layer "F.Fab")
			(hide yes)
			(effects
				(font
					(size 1 1)
					(thickness 0.15)
				)
			)
		)
		(property "Tolerance" "1%"
			(at 0 0 0)
			(layer "F.Fab")
			(hide yes)
			(effects
				(font
					(size 1 1)
					(thickness 0.15)
				)
			)
		)
		(property "Val" "499k"
			(at 0 0 0)
			(layer "F.Fab")
			(hide yes)
			(effects
				(font
					(size 1 1)
					(thickness 0.15)
				)
			)
		)
		(sheetname "Supply")
		(sheetfile "supply.kicad_sch")
		(attr smd)
		(fp_rect
			(start -0.925 -0.47)
			(end 0.925 0.47)
			(stroke
				(width 0.05)
				(type default)
			)
			(fill none)
			(layer "F.CrtYd")
		)
		(fp_rect
			(start -0.5 -0.25)
			(end 0.5 0.25)
			(stroke
				(width 0.15)
				(type solid)
			)
			(fill none)
			(layer "F.Fab")
		)
		(fp_text user "${REFERENCE}"
			(at -0.95 3.168 0)
			(layer "F.Fab")
			(hide yes)
			(effects
				(font
					(size 0.7 0.7)
					(thickness 0.15)
				)
				(justify left bottom)
			)
		)
		(fp_text user "License: Apache-2.0"
			(at -0.95 5.169 0)
			(layer "F.Fab")
			(hide yes)
			(effects
				(font
					(size 0.7 0.7)
					(thickness 0.15)
				)
				(justify left bottom)
			)
		)
		(fp_text user "Author: Antmicro"
			(at -0.95 4.169 0)
			(layer "F.Fab")
			(hide yes)
			(effects
				(font
					(size 0.7 0.7)
					(thickness 0.15)
				)
				(justify left bottom)
			)
		)
		(pad "1" smd roundrect
			(at -0.48 0)
			(size 0.59 0.64)
			(layers "F.Cu" "F.Paste" "F.Mask")
			(roundrect_rratio 0.25)
			(net 1 "GND")
			(pintype "passive")
		)
		(pad "2" smd roundrect
			(at 0.48 0)
			(size 0.59 0.64)
			(layers "F.Cu" "F.Paste" "F.Mask")
			(roundrect_rratio 0.25)
			(net 767 "/Supply/5V_MODE2")
			(pintype "passive")
		)
	)
	(footprint "antmicro-footprints:R_0402_1005Metric"
		(layer "F.Cu")
		(at 65.535 116.3 -90)
		(descr "Resistor SMD 0402")
		(tags "resistor SMD 0402")
		(property "Reference" "R84"
			(at 1.075 0.485 -90)
			(layer "F.SilkS")
			(effects
				(font
					(size 0.7 0.7)
					(thickness 0.15)
				)
				(justify left bottom)
			)
		)
		(property "Value" "R_0R_0402"
			(at 0 1.4 -90)
			(layer "F.Fab")
			(effects
				(font
					(size 0.7 0.7)
					(thickness 0.15)
				)
				(justify left bottom)
			)
		)
		(property "Footprint" "antmicro-footprints:R_0402_1005Metric"
			(at 0 0 -90)
			(layer "F.Fab")
			(hide yes)
			(effects
				(font
					(size 1.27 1.27)
					(thickness 0.15)
				)
			)
		)
		(property "Datasheet" "https://industrial.panasonic.com/cdbs/www-data/pdf/RDA0000/AOA0000C301.pdf"
			(at 0 0 -90)
			(layer "F.Fab")
			(hide yes)
			(effects
				(font
					(size 1.27 1.27)
					(thickness 0.15)
				)
			)
		)
		(property "Author" "Antmicro"
			(at -50.765 181.835 0)
			(layer "F.Fab")
			(hide yes)
			(effects
				(font
					(size 1 1)
					(thickness 0.15)
				)
			)
		)
		(property "Current" "1A"
			(at -50.765 181.835 0)
			(layer "F.Fab")
			(hide yes)
			(effects
				(font
					(size 1 1)
					(thickness 0.15)
				)
			)
		)
		(property "License" "Apache-2.0"
			(at -50.765 181.835 0)
			(layer "F.Fab")
			(hide yes)
			(effects
				(font
					(size 1 1)
					(thickness 0.15)
				)
			)
		)
		(property "MPN" "ERJ2GE0R00X"
			(at -50.765 181.835 0)
			(layer "F.Fab")
			(hide yes)
			(effects
				(font
					(size 1 1)
					(thickness 0.15)
				)
			)
		)
		(property "Manufacturer" "Panasonic"
			(at -50.765 181.835 0)
			(layer "F.Fab")
			(hide yes)
			(effects
				(font
					(size 1 1)
					(thickness 0.15)
				)
			)
		)
		(property "Tolerance" ""
			(at -50.765 181.835 0)
			(layer "F.Fab")
			(hide yes)
			(effects
				(font
					(size 1 1)
					(thickness 0.15)
				)
			)
		)
		(property "Val" "0R"
			(at -50.765 181.835 0)
			(layer "F.Fab")
			(hide yes)
			(effects
				(font
					(size 1 1)
					(thickness 0.15)
				)
			)
		)
		(sheetname "USB Debug, DP")
		(sheetfile "usb.kicad_sch")
		(attr smd)
		(fp_rect
			(start -0.925 -0.47)
			(end 0.925 0.47)
			(stroke
				(width 0.05)
				(type default)
			)
			(fill none)
			(layer "F.CrtYd")
		)
		(fp_rect
			(start -0.5 -0.25)
			(end 0.5 0.25)
			(stroke
				(width 0.15)
				(type solid)
			)
			(fill none)
			(layer "F.Fab")
		)
		(fp_text user "${REFERENCE}"
			(at -0.95 3.168 -90)
			(layer "F.Fab")
			(hide yes)
			(effects
				(font
					(size 0.7 0.7)
					(thickness 0.15)
				)
				(justify left bottom)
			)
		)
		(fp_text user "License: Apache-2.0"
			(at -0.95 5.169 -90)
			(layer "F.Fab")
			(hide yes)
			(effects
				(font
					(size 0.7 0.7)
					(thickness 0.15)
				)
				(justify left bottom)
			)
		)
		(fp_text user "Author: Antmicro"
			(at -0.95 4.169 -90)
			(layer "F.Fab")
			(hide yes)
			(effects
				(font
					(size 0.7 0.7)
					(thickness 0.15)
				)
				(justify left bottom)
			)
		)
		(pad "1" smd roundrect
			(at -0.48 0 270)
			(size 0.59 0.64)
			(layers "F.Cu" "F.Paste" "F.Mask")
			(roundrect_rratio 0.25)
			(net 553 "/USB Debug, DP/USBC0_5V_PEN")
			(pintype "passive")
		)
		(pad "2" smd roundrect
			(at 0.48 0 270)
			(size 0.59 0.64)
			(layers "F.Cu" "F.Paste" "F.Mask")
			(roundrect_rratio 0.25)
			(net 673 "Net-(U12-EN)")
			(pintype "passive")
		)
	)
	(footprint "antmicro-footprints:C_0402_1005Metric"
		(layer "F.Cu")
		(at 62.69 94.35 180)
		(descr "Capacitor SMD 0402")
		(tags "capacitor SMD 0402")
		(property "Reference" "C6"
			(at -2.32 -0.37 0)
			(layer "F.SilkS")
			(effects
				(font
					(size 0.7 0.7)
					(thickness 0.15)
				)
				(justify right bottom)
			)
		)
		(property "Value" "C_100n_0402"
			(at -1.022927 2.155213 0)
			(layer "F.Fab")
			(effects
				(font
					(size 0.7 0.7)
					(thickness 0.15)
				)
				(justify right bottom)
			)
		)
		(property "Footprint" "antmicro-footprints:C_0402_1005Metric"
			(at 0 0 180)
			(layer "F.Fab")
			(hide yes)
			(effects
				(font
					(size 1.27 1.27)
					(thickness 0.15)
				)
			)
		)
		(property "Datasheet" "https://www.murata.com/products/productdetail?partno=GRM155R61H104KE14%23"
			(at 0 0 180)
			(layer "F.Fab")
			(hide yes)
			(effects
				(font
					(size 1.27 1.27)
					(thickness 0.15)
				)
			)
		)
		(property "Author" "Antmicro"
			(at 125.38 188.72 0)
			(layer "F.Fab")
			(hide yes)
			(effects
				(font
					(size 1 1)
					(thickness 0.15)
				)
			)
		)
		(property "Dielectric" "X5R"
			(at 125.38 188.72 0)
			(layer "F.Fab")
			(hide yes)
			(effects
				(font
					(size 1 1)
					(thickness 0.15)
				)
			)
		)
		(property "License" "Apache-2.0"
			(at 125.38 188.72 0)
			(layer "F.Fab")
			(hide yes)
			(effects
				(font
					(size 1 1)
					(thickness 0.15)
				)
			)
		)
		(property "MPN" "GRM155R61H104KE14D"
			(at 125.38 188.72 0)
			(layer "F.Fab")
			(hide yes)
			(effects
				(font
					(size 1 1)
					(thickness 0.15)
				)
			)
		)
		(property "Manufacturer" "Murata"
			(at 125.38 188.72 0)
			(layer "F.Fab")
			(hide yes)
			(effects
				(font
					(size 1 1)
					(thickness 0.15)
				)
			)
		)
		(property "Val" "100n"
			(at 125.38 188.72 0)
			(layer "F.Fab")
			(hide yes)
			(effects
				(font
					(size 1 1)
					(thickness 0.15)
				)
			)
		)
		(property "Voltage" "50V"
			(at 125.38 188.72 0)
			(layer "F.Fab")
			(hide yes)
			(effects
				(font
					(size 1 1)
					(thickness 0.15)
				)
			)
		)
		(sheetname "Supply")
		(sheetfile "supply.kicad_sch")
		(attr smd)
		(fp_rect
			(start -0.925 -0.47)
			(end 0.925 0.47)
			(stroke
				(width 0.05)
				(type default)
			)
			(fill none)
			(layer "F.CrtYd")
		)
		(fp_line
			(start 0.504 0.248)
			(end -0.494 0.248)
			(stroke
				(width 0.15)
				(type solid)
			)
			(layer "F.Fab")
		)
		(fp_line
			(start 0.504 -0.25)
			(end 0.504 0.248)
			(stroke
				(width 0.15)
				(type solid)
			)
			(layer "F.Fab")
		)
		(fp_line
			(start -0.494 0.248)
			(end -0.494 -0.25)
			(stroke
				(width 0.15)
				(type solid)
			)
			(layer "F.Fab")
		)
		(fp_line
			(start -0.494 -0.25)
			(end 0.504 -0.25)
			(stroke
				(width 0.15)
				(type solid)
			)
			(layer "F.Fab")
		)
		(fp_text user "${REFERENCE}"
			(at -0.939 4.599 0)
			(layer "F.Fab")
			(hide yes)
			(effects
				(font
					(size 0.7 0.7)
					(thickness 0.15)
				)
				(justify right bottom)
			)
		)
		(fp_text user "License: Apache-2.0"
			(at -0.939 5.799 0)
			(layer "F.Fab")
			(hide yes)
			(effects
				(font
					(size 0.7 0.7)
					(thickness 0.15)
				)
				(justify right bottom)
			)
		)
		(fp_text user "Author: Antmicro"
			(at -0.939 3.399 0)
			(layer "F.Fab")
			(hide yes)
			(effects
				(font
					(size 0.7 0.7)
					(thickness 0.15)
				)
				(justify right bottom)
			)
		)
		(pad "1" smd roundrect
			(at -0.48 0 180)
			(size 0.59 0.64)
			(layers "F.Cu" "F.Paste" "F.Mask")
			(roundrect_rratio 0.25)
			(net 115 "VCC")
			(pintype "passive")
		)
		(pad "2" smd roundrect
			(at 0.48 0 180)
			(size 0.59 0.64)
			(layers "F.Cu" "F.Paste" "F.Mask")
			(roundrect_rratio 0.25)
			(net 1 "GND")
			(pintype "passive")
		)
	)
)
